(kicad_pcb
	(version 20260206)
	(generator "pcbnew")
	(generator_version "10.0")
	(general
		(thickness 1.6)
		(legacy_teardrops no)
	)
	(paper "A4")
	(title_block
		(title "9054_F0T_PDB_BD_GPU_F_V04_1213_1550_OCP.brd")
		(comment 1 "Grand Teton / footprints 606-608 of 608")
	)
	(layers
		(0 "F.Cu" signal "TOP")
		(4 "In1.Cu" signal "GND")
		(6 "In2.Cu" signal "IN1")
		(8 "In3.Cu" signal "GND1")
		(10 "In4.Cu" signal "VCC")
		(12 "In5.Cu" signal "VCC1")
		(14 "In6.Cu" signal "GND2")
		(16 "In7.Cu" signal "IN2")
		(18 "In8.Cu" signal "GND3")
		(2 "B.Cu" signal "BOTTOM")
		(9 "F.Adhes" user "F.Adhesive")
		(11 "B.Adhes" user "B.Adhesive")
		(13 "F.Paste" user "Package Geometry/Pastemask Top")
		(15 "B.Paste" user "Package Geometry/Pastemask Bottom")
		(5 "F.SilkS" user "Ref Des/Silkscreen Top")
		(7 "B.SilkS" user "Ref Des/Silkscreen Bottom")
		(1 "F.Mask" user "Board Geometry/Soldermask Top")
		(3 "B.Mask" user "Board Geometry/Soldermask Bottom")
		(17 "Dwgs.User" user "User.Drawings")
		(19 "Cmts.User" user "User.Comments")
		(21 "Eco1.User" user "User.Eco1")
		(23 "Eco2.User" user "User.Eco2")
		(25 "Edge.Cuts" user "Board Geometry/Outline")
		(27 "Margin" user)
		(31 "F.CrtYd" user "Package Geometry/Place Bound Top")
		(29 "B.CrtYd" user "Package Geometry/Place Bound Bottom")
		(35 "F.Fab" user "Ref Des/Assembly Top")
		(33 "B.Fab" user "Ref Des/Assembly Bottom")
	)
	(footprint ""
		(layer "B.Cu")
		(at 281.178 -91.059 -90)
		(property "Reference" "C90"
			(at 0 0 90)
			(layer "B.SilkS")
			(hide yes)
			(effects
				(font
					(size 1.27 1.27)
				)
				(justify mirror)
			)
		)
		(property "Value" ""
			(at 0 0 90)
			(layer "B.Fab")
			(effects
				(font
					(size 1.27 1.27)
				)
				(justify mirror)
			)
		)
		(duplicate_pad_numbers_are_jumpers no)
		(fp_line
			(start -1.2954 0.5842)
			(end 1.2954 0.5842)
			(stroke
				(width 0.1524)
				(type default)
			)
			(layer "B.SilkS")
		)
		(fp_line
			(start 1.2954 0.5842)
			(end 1.2954 -0.5842)
			(stroke
				(width 0.1524)
				(type default)
			)
			(layer "B.SilkS")
		)
		(fp_line
			(start -1.2954 -0.5842)
			(end -1.2954 0.5842)
			(stroke
				(width 0.1524)
				(type default)
			)
			(layer "B.SilkS")
		)
		(fp_line
			(start 1.2954 -0.5842)
			(end -1.2954 -0.5842)
			(stroke
				(width 0.1524)
				(type default)
			)
			(layer "B.SilkS")
		)
		(fp_line
			(start -0.8636 0.4572)
			(end 0.8636 0.4572)
			(stroke
				(width 0.1)
				(type default)
			)
			(layer "B.Fab")
		)
		(fp_line
			(start 0.8636 0.4572)
			(end 0.8636 0.4064)
			(stroke
				(width 0.1)
				(type default)
			)
			(layer "B.Fab")
		)
		(fp_line
			(start -1.1938 0.4064)
			(end -0.8636 0.4064)
			(stroke
				(width 0.1)
				(type default)
			)
			(layer "B.Fab")
		)
		(fp_line
			(start -0.8636 0.4064)
			(end -0.8636 0.4572)
			(stroke
				(width 0.1)
				(type default)
			)
			(layer "B.Fab")
		)
		(fp_line
			(start 0.8636 0.4064)
			(end 1.1938 0.4064)
			(stroke
				(width 0.1)
				(type default)
			)
			(layer "B.Fab")
		)
		(fp_line
			(start 1.1938 0.4064)
			(end 1.1938 -0.4064)
			(stroke
				(width 0.1)
				(type default)
			)
			(layer "B.Fab")
		)
		(fp_line
			(start -1.1938 -0.4064)
			(end -1.1938 0.4064)
			(stroke
				(width 0.1)
				(type default)
			)
			(layer "B.Fab")
		)
		(fp_line
			(start -0.8636 -0.4064)
			(end -1.1938 -0.4064)
			(stroke
				(width 0.1)
				(type default)
			)
			(layer "B.Fab")
		)
		(fp_line
			(start 0.8636 -0.4064)
			(end 0.8636 -0.4572)
			(stroke
				(width 0.1)
				(type default)
			)
			(layer "B.Fab")
		)
		(fp_line
			(start 1.1938 -0.4064)
			(end 0.8636 -0.4064)
			(stroke
				(width 0.1)
				(type default)
			)
			(layer "B.Fab")
		)
		(fp_line
			(start -0.8636 -0.4572)
			(end -0.8636 -0.4064)
			(stroke
				(width 0.1)
				(type default)
			)
			(layer "B.Fab")
		)
		(fp_line
			(start 0.8636 -0.4572)
			(end -0.8636 -0.4572)
			(stroke
				(width 0.1)
				(type default)
			)
			(layer "B.Fab")
		)
		(pad "1" smd rect
			(at 0.7366 0 180)
			(size 0.7112 0.8128)
			(layers "B.Cu" "B.Mask" "B.Paste")
			(net "FM_HS1_EN_BUSBAR")
		)
		(pad "2" smd rect
			(at -0.7366 0 180)
			(size 0.7112 0.8128)
			(layers "B.Cu" "B.Mask" "B.Paste")
			(net "GND")
		)
	)
	(footprint ""
		(layer "B.Cu")
		(at 274.8534 -76.454 -90)
		(property "Reference" "PR482"
			(at 0 0 90)
			(layer "B.SilkS")
			(hide yes)
			(effects
				(font
					(size 1.27 1.27)
				)
				(justify mirror)
			)
		)
		(property "Value" ""
			(at 0 0 90)
			(layer "B.Fab")
			(effects
				(font
					(size 1.27 1.27)
				)
				(justify mirror)
			)
		)
		(duplicate_pad_numbers_are_jumpers no)
		(fp_line
			(start -0.7874 0.4064)
			(end 0.7874 0.4064)
			(stroke
				(width 0.1524)
				(type default)
			)
			(layer "B.SilkS")
		)
		(fp_line
			(start 0.7874 0.4064)
			(end 0.7874 -0.4064)
			(stroke
				(width 0.1524)
				(type default)
			)
			(layer "B.SilkS")
		)
		(fp_line
			(start -0.7874 -0.4064)
			(end -0.7874 0.4064)
			(stroke
				(width 0.1524)
				(type default)
			)
			(layer "B.SilkS")
		)
		(fp_line
			(start 0.7874 -0.4064)
			(end -0.7874 -0.4064)
			(stroke
				(width 0.1524)
				(type default)
			)
			(layer "B.SilkS")
		)
		(fp_line
			(start -0.67945 0.3048)
			(end -0.120396 0.3048)
			(stroke
				(width 0.1)
				(type default)
			)
			(layer "B.Fab")
		)
		(fp_line
			(start -0.120396 0.3048)
			(end -0.120396 0.2794)
			(stroke
				(width 0.1)
				(type default)
			)
			(layer "B.Fab")
		)
		(fp_line
			(start 0.12065 0.3048)
			(end 0.67945 0.3048)
			(stroke
				(width 0.1)
				(type default)
			)
			(layer "B.Fab")
		)
		(fp_line
			(start 0.67945 0.3048)
			(end 0.67945 -0.305054)
			(stroke
				(width 0.1)
				(type default)
			)
			(layer "B.Fab")
		)
		(fp_line
			(start -0.120396 0.2794)
			(end 0.12065 0.2794)
			(stroke
				(width 0.1)
				(type default)
			)
			(layer "B.Fab")
		)
		(fp_line
			(start 0.12065 0.2794)
			(end 0.12065 0.3048)
			(stroke
				(width 0.1)
				(type default)
			)
			(layer "B.Fab")
		)
		(fp_line
			(start -0.12065 -0.2794)
			(end -0.12065 -0.3048)
			(stroke
				(width 0.1)
				(type default)
			)
			(layer "B.Fab")
		)
		(fp_line
			(start 0.12065 -0.2794)
			(end -0.12065 -0.2794)
			(stroke
				(width 0.1)
				(type default)
			)
			(layer "B.Fab")
		)
		(fp_line
			(start -0.67945 -0.3048)
			(end -0.67945 0.3048)
			(stroke
				(width 0.1)
				(type default)
			)
			(layer "B.Fab")
		)
		(fp_line
			(start -0.12065 -0.3048)
			(end -0.67945 -0.3048)
			(stroke
				(width 0.1)
				(type default)
			)
			(layer "B.Fab")
		)
		(fp_line
			(start 0.12065 -0.305054)
			(end 0.12065 -0.2794)
			(stroke
				(width 0.1)
				(type default)
			)
			(layer "B.Fab")
		)
		(fp_line
			(start 0.67945 -0.305054)
			(end 0.12065 -0.305054)
			(stroke
				(width 0.1)
				(type default)
			)
			(layer "B.Fab")
		)
		(pad "1" smd circle
			(at 0.40005 0 90)
			(size 0 0)
			(layers "B.Cu" "B.Mask" "B.Paste")
			(net "P52V_HS1_OV")
		)
		(pad "2" smd circle
			(at -0.40005 0 90)
			(size 0 0)
			(layers "B.Cu" "B.Mask" "B.Paste")
			(net "GND_FIELD_SIGNAL")
		)
	)
	(footprint ""
		(layer "B.Cu")
		(at 445.5414 -47.625 180)
		(property "Reference" "U40"
			(at -0.4445 -2.50317 0)
			(unlocked yes)
			(layer "B.SilkS")
			(effects
				(font
					(size 0.7874 0.5842)
					(thickness 0.1524)
				)
				(justify left mirror)
			)
		)
		(property "Value" ""
			(at 0 0 0)
			(layer "B.Fab")
			(effects
				(font
					(size 1.27 1.27)
				)
				(justify mirror)
			)
		)
		(duplicate_pad_numbers_are_jumpers no)
		(fp_line
			(start 1.733296 1.549908)
			(end -1.733296 1.549908)
			(stroke
				(width 0.1524)
				(type default)
			)
			(layer "B.SilkS")
		)
		(fp_line
			(start 1.733296 -1.549908)
			(end 1.733296 1.549908)
			(stroke
				(width 0.1524)
				(type default)
			)
			(layer "B.SilkS")
		)
		(fp_line
			(start 0.660908 -1.549908)
			(end 1.733296 -1.549908)
			(stroke
				(width 0.1524)
				(type default)
			)
			(layer "B.SilkS")
		)
		(fp_line
			(start 0 -0.889)
			(end 0.660908 -1.549908)
			(stroke
				(width 0.1524)
				(type default)
			)
			(layer "B.SilkS")
		)
		(fp_line
			(start -0.660908 -1.549908)
			(end 0 -0.889)
			(stroke
				(width 0.1524)
				(type default)
			)
			(layer "B.SilkS")
		)
		(fp_line
			(start -1.733296 1.549908)
			(end -1.733296 -1.549908)
			(stroke
				(width 0.1524)
				(type default)
			)
			(layer "B.SilkS")
		)
		(fp_line
			(start -1.733296 -1.549908)
			(end -0.660908 -1.549908)
			(stroke
				(width 0.1524)
				(type default)
			)
			(layer "B.SilkS")
		)
		(fp_poly
			(pts
				(xy 2.4384 -1.20396) (xy 2.4384 -0.69596) (xy 1.9304 -0.94996)
			)
			(stroke
				(width 0)
				(type default)
			)
			(fill yes)
			(layer "B.SilkS")
		)
		(fp_line
			(start 0.849884 1.549908)
			(end -0.849884 1.549908)
			(stroke
				(width 0.1)
				(type default)
			)
			(layer "B.Fab")
		)
		(fp_line
			(start 0.849884 -1.549908)
			(end 0.849884 1.549908)
			(stroke
				(width 0.1)
				(type default)
			)
			(layer "B.Fab")
		)
		(fp_line
			(start -0.849884 1.549908)
			(end -0.849884 -1.549908)
			(stroke
				(width 0.1)
				(type default)
			)
			(layer "B.Fab")
		)
		(fp_line
			(start -0.849884 -1.549908)
			(end 0.849884 -1.549908)
			(stroke
				(width 0.1)
				(type default)
			)
			(layer "B.Fab")
		)
		(fp_poly
			(pts
				(xy 2.4384 -1.20396) (xy 2.4384 -0.69596) (xy 1.9304 -0.94996)
			)
			(stroke
				(width 0)
				(type default)
			)
			(fill yes)
			(layer "B.Fab")
		)
		(pad "1" smd rect
			(at 1.199896 -0.94996 90)
			(size 0.5588 0.8128)
			(layers "B.Cu" "B.Mask" "B.Paste")
			(net "FAN_PWR_EN_BUF_R")
		)
		(pad "2" smd rect
			(at 1.199896 0 90)
			(size 0.5588 0.8128)
			(layers "B.Cu" "B.Mask" "B.Paste")
			(net "P3V3_HPDB_PG_R1")
		)
		(pad "3" smd rect
			(at 1.199896 0.94996 90)
			(size 0.5588 0.8128)
			(layers "B.Cu" "B.Mask" "B.Paste")
			(net "GND")
		)
		(pad "4" smd rect
			(at -1.199896 0.94996 90)
			(size 0.5588 0.8128)
			(layers "B.Cu" "B.Mask" "B.Paste")
			(net "P12V_LED_EN_BUF")
		)
		(pad "5" smd rect
			(at -1.199896 -0.94996 90)
			(size 0.5588 0.8128)
			(layers "B.Cu" "B.Mask" "B.Paste")
			(net "P3V3_AUX")
		)
	)
)
